(kicad_pcb
	(version 20260206)
	(generator "pcbnew")
	(generator_version "10.0")
	(general
		(thickness 1.6)
		(legacy_teardrops no)
	)
	(paper "A4")
	(title_block
		(title "04192023_DAF0TMB3IC0_F0TG_MB_C_brd_V02_OCP.brd")
		(comment 1 "Grand Teton / footprints 3937-3943 of 8354")
	)
	(layers
		(0 "F.Cu" signal "TOP")
		(4 "In1.Cu" signal "GND")
		(6 "In2.Cu" signal "IN1")
		(8 "In3.Cu" signal "GND1")
		(10 "In4.Cu" signal "IN2")
		(12 "In5.Cu" signal "GND2")
		(14 "In6.Cu" signal "IN3")
		(16 "In7.Cu" signal "GND3")
		(18 "In8.Cu" signal "VCC")
		(20 "In9.Cu" signal "VCC1")
		(22 "In10.Cu" signal "GND4")
		(24 "In11.Cu" signal "IN4")
		(26 "In12.Cu" signal "GND5")
		(28 "In13.Cu" signal "IN5")
		(30 "In14.Cu" signal "GND6")
		(32 "In15.Cu" signal "IN6")
		(34 "In16.Cu" signal "GND7")
		(2 "B.Cu" signal "BOTTOM")
		(9 "F.Adhes" user "F.Adhesive")
		(11 "B.Adhes" user "B.Adhesive")
		(13 "F.Paste" user "Package Geometry/Pastemask Top")
		(15 "B.Paste" user "Package Geometry/Pastemask Bottom")
		(5 "F.SilkS" user "Ref Des/Silkscreen Top")
		(7 "B.SilkS" user "Ref Des/Silkscreen Bottom")
		(1 "F.Mask" user "Board Geometry/Soldermask Top")
		(3 "B.Mask" user "Board Geometry/Soldermask Bottom")
		(17 "Dwgs.User" user "User.Drawings")
		(19 "Cmts.User" user "User.Comments")
		(21 "Eco1.User" user "User.Eco1")
		(23 "Eco2.User" user "User.Eco2")
		(25 "Edge.Cuts" user "Board Geometry/Outline")
		(27 "Margin" user)
		(31 "F.CrtYd" user "Package Geometry/Place Bound Top")
		(29 "B.CrtYd" user "Package Geometry/Place Bound Bottom")
		(35 "F.Fab" user "Ref Des/Assembly Top")
		(33 "B.Fab" user "Ref Des/Assembly Bottom")
	)
	(footprint ""
		(layer "F.Cu")
		(at 479.445066 -297.569128 180)
		(property "Reference" "DB4"
			(at -3.05943 -2.144014 0)
			(unlocked yes)
			(layer "F.SilkS")
			(effects
				(font
					(size 0.7874 0.5842)
					(thickness 0.1524)
				)
				(justify left)
			)
		)
		(property "Value" ""
			(at 0 0 180)
			(layer "F.Fab")
			(effects
				(font
					(size 1.27 1.27)
				)
			)
		)
		(duplicate_pad_numbers_are_jumpers no)
		(fp_line
			(start 3.330702 -4.771136)
			(end 3.21564 -4.46786)
			(stroke
				(width 0.1524)
				(type default)
			)
			(layer "F.SilkS")
		)
		(fp_line
			(start 2.502916 -2.588514)
			(end 0 4.011168)
			(stroke
				(width 0.1524)
				(type default)
			)
			(layer "F.SilkS")
		)
		(fp_line
			(start 0 4.011168)
			(end -3.330702 -4.771136)
			(stroke
				(width 0.1524)
				(type default)
			)
			(layer "F.SilkS")
		)
		(fp_line
			(start -3.330702 -4.771136)
			(end 3.330702 -4.771136)
			(stroke
				(width 0.1524)
				(type default)
			)
			(layer "F.SilkS")
		)
		(fp_line
			(start 3.330702 -4.771136)
			(end 0 4.011168)
			(stroke
				(width 0.1)
				(type default)
			)
			(layer "F.Fab")
		)
		(fp_line
			(start 0 4.011168)
			(end -3.330702 -4.771136)
			(stroke
				(width 0.1)
				(type default)
			)
			(layer "F.Fab")
		)
		(fp_line
			(start -3.330702 -4.771136)
			(end 3.330702 -4.771136)
			(stroke
				(width 0.1)
				(type default)
			)
			(layer "F.Fab")
		)
		(pad "1" thru_hole circle
			(at 0 0 180)
			(size 2.159 2.159)
			(drill 1.7018)
			(layers "*.Cu" "*.Mask")
			(remove_unused_layers no)
			(net "T1_GND")
			(clearance 0.0254)
			(thermal_gap 0.0254)
		)
		(pad "2" thru_hole circle
			(at -1.27 -3.348736 180)
			(size 2.159 2.159)
			(drill 1.7018)
			(layers "*.Cu" "*.Mask")
			(remove_unused_layers no)
			(net "TDR_SE_45_OHM_IN3")
			(clearance 0.0254)
			(thermal_gap 0.0254)
		)
		(pad "3" thru_hole circle
			(at 1.27 -3.348736 180)
			(size 2.159 2.159)
			(drill 1.7018)
			(layers "*.Cu" "*.Mask")
			(remove_unused_layers no)
			(net "TDR_SE_45_OHM_IN3")
			(clearance 0.0254)
			(thermal_gap 0.0254)
		)
	)
	(footprint ""
		(layer "F.Cu")
		(at 106.934 -416.306 180)
		(property "Reference" "C83"
			(at 0 0 180)
			(layer "F.SilkS")
			(hide yes)
			(effects
				(font
					(size 1.27 1.27)
				)
			)
		)
		(property "Value" ""
			(at 0 0 180)
			(layer "F.Fab")
			(effects
				(font
					(size 1.27 1.27)
				)
			)
		)
		(duplicate_pad_numbers_are_jumpers no)
		(fp_line
			(start 0.7874 0.4064)
			(end -0.7874 0.4064)
			(stroke
				(width 0.1524)
				(type default)
			)
			(layer "F.SilkS")
		)
		(fp_line
			(start 0.7874 -0.4064)
			(end 0.7874 0.4064)
			(stroke
				(width 0.1524)
				(type default)
			)
			(layer "F.SilkS")
		)
		(fp_line
			(start -0.7874 0.4064)
			(end -0.7874 -0.4064)
			(stroke
				(width 0.1524)
				(type default)
			)
			(layer "F.SilkS")
		)
		(fp_line
			(start -0.7874 -0.4064)
			(end 0.7874 -0.4064)
			(stroke
				(width 0.1524)
				(type default)
			)
			(layer "F.SilkS")
		)
		(fp_line
			(start 0.67945 0.3048)
			(end 0.120396 0.3048)
			(stroke
				(width 0.1)
				(type default)
			)
			(layer "F.Fab")
		)
		(fp_line
			(start 0.67945 -0.3048)
			(end 0.67945 0.3048)
			(stroke
				(width 0.1)
				(type default)
			)
			(layer "F.Fab")
		)
		(fp_line
			(start 0.12065 -0.2794)
			(end 0.12065 -0.3048)
			(stroke
				(width 0.1)
				(type default)
			)
			(layer "F.Fab")
		)
		(fp_line
			(start 0.12065 -0.3048)
			(end 0.67945 -0.3048)
			(stroke
				(width 0.1)
				(type default)
			)
			(layer "F.Fab")
		)
		(fp_line
			(start 0.120396 0.3048)
			(end 0.120396 0.2794)
			(stroke
				(width 0.1)
				(type default)
			)
			(layer "F.Fab")
		)
		(fp_line
			(start 0.120396 0.2794)
			(end -0.12065 0.2794)
			(stroke
				(width 0.1)
				(type default)
			)
			(layer "F.Fab")
		)
		(fp_line
			(start -0.12065 0.3048)
			(end -0.67945 0.3048)
			(stroke
				(width 0.1)
				(type default)
			)
			(layer "F.Fab")
		)
		(fp_line
			(start -0.12065 0.2794)
			(end -0.12065 0.3048)
			(stroke
				(width 0.1)
				(type default)
			)
			(layer "F.Fab")
		)
		(fp_line
			(start -0.12065 -0.2794)
			(end 0.12065 -0.2794)
			(stroke
				(width 0.1)
				(type default)
			)
			(layer "F.Fab")
		)
		(fp_line
			(start -0.12065 -0.305054)
			(end -0.12065 -0.2794)
			(stroke
				(width 0.1)
				(type default)
			)
			(layer "F.Fab")
		)
		(fp_line
			(start -0.67945 0.3048)
			(end -0.67945 -0.305054)
			(stroke
				(width 0.1)
				(type default)
			)
			(layer "F.Fab")
		)
		(fp_line
			(start -0.67945 -0.305054)
			(end -0.12065 -0.305054)
			(stroke
				(width 0.1)
				(type default)
			)
			(layer "F.Fab")
		)
		(pad "1" smd circle
			(at -0.40005 0 180)
			(size 0 0)
			(layers "F.Cu" "F.Mask" "F.Paste")
			(net "P3V3_9ZXL045_P1_VDDR")
		)
		(pad "2" smd circle
			(at 0.40005 0 180)
			(size 0 0)
			(layers "F.Cu" "F.Mask" "F.Paste")
			(net "GND")
		)
	)
	(footprint ""
		(layer "F.Cu")
		(at 118.363238 -41.17975 90)
		(property "Reference" "R6281"
			(at 0 0 90)
			(layer "F.SilkS")
			(hide yes)
			(effects
				(font
					(size 1.27 1.27)
				)
			)
		)
		(property "Value" ""
			(at 0 0 90)
			(layer "F.Fab")
			(effects
				(font
					(size 1.27 1.27)
				)
			)
		)
		(duplicate_pad_numbers_are_jumpers no)
		(fp_line
			(start 0.7874 -0.4064)
			(end 0.7874 0.4064)
			(stroke
				(width 0.1524)
				(type default)
			)
			(layer "F.SilkS")
		)
		(fp_line
			(start -0.7874 -0.4064)
			(end 0.7874 -0.4064)
			(stroke
				(width 0.1524)
				(type default)
			)
			(layer "F.SilkS")
		)
		(fp_line
			(start 0.7874 0.4064)
			(end -0.7874 0.4064)
			(stroke
				(width 0.1524)
				(type default)
			)
			(layer "F.SilkS")
		)
		(fp_line
			(start -0.7874 0.4064)
			(end -0.7874 -0.4064)
			(stroke
				(width 0.1524)
				(type default)
			)
			(layer "F.SilkS")
		)
		(fp_line
			(start -0.12065 -0.305054)
			(end -0.12065 -0.2794)
			(stroke
				(width 0.1)
				(type default)
			)
			(layer "F.Fab")
		)
		(fp_line
			(start -0.67945 -0.305054)
			(end -0.12065 -0.305054)
			(stroke
				(width 0.1)
				(type default)
			)
			(layer "F.Fab")
		)
		(fp_line
			(start 0.67945 -0.3048)
			(end 0.67945 0.3048)
			(stroke
				(width 0.1)
				(type default)
			)
			(layer "F.Fab")
		)
		(fp_line
			(start 0.12065 -0.3048)
			(end 0.67945 -0.3048)
			(stroke
				(width 0.1)
				(type default)
			)
			(layer "F.Fab")
		)
		(fp_line
			(start 0.12065 -0.2794)
			(end 0.12065 -0.3048)
			(stroke
				(width 0.1)
				(type default)
			)
			(layer "F.Fab")
		)
		(fp_line
			(start -0.12065 -0.2794)
			(end 0.12065 -0.2794)
			(stroke
				(width 0.1)
				(type default)
			)
			(layer "F.Fab")
		)
		(fp_line
			(start 0.120396 0.2794)
			(end -0.12065 0.2794)
			(stroke
				(width 0.1)
				(type default)
			)
			(layer "F.Fab")
		)
		(fp_line
			(start -0.12065 0.2794)
			(end -0.12065 0.3048)
			(stroke
				(width 0.1)
				(type default)
			)
			(layer "F.Fab")
		)
		(fp_line
			(start 0.67945 0.3048)
			(end 0.120396 0.3048)
			(stroke
				(width 0.1)
				(type default)
			)
			(layer "F.Fab")
		)
		(fp_line
			(start 0.120396 0.3048)
			(end 0.120396 0.2794)
			(stroke
				(width 0.1)
				(type default)
			)
			(layer "F.Fab")
		)
		(fp_line
			(start -0.12065 0.3048)
			(end -0.67945 0.3048)
			(stroke
				(width 0.1)
				(type default)
			)
			(layer "F.Fab")
		)
		(fp_line
			(start -0.67945 0.3048)
			(end -0.67945 -0.305054)
			(stroke
				(width 0.1)
				(type default)
			)
			(layer "F.Fab")
		)
		(pad "1" smd circle
			(at -0.40005 0 90)
			(size 0 0)
			(layers "F.Cu" "F.Mask" "F.Paste")
			(net "USB_HUB2_TI_SMBUSZ_MRP_PROG_FUNC2")
		)
		(pad "2" smd circle
			(at 0.40005 0 90)
			(size 0 0)
			(layers "F.Cu" "F.Mask" "F.Paste")
			(net "GND")
		)
	)
	(footprint ""
		(layer "F.Cu")
		(at 277.895304 -153.766012)
		(property "Reference" "H125"
			(at 5.0038 5.03047 0)
			(unlocked yes)
			(layer "F.SilkS")
			(effects
				(font
					(size 0.7874 0.5842)
					(thickness 0.1524)
				)
				(justify left)
			)
		)
		(property "Value" ""
			(at 0 0 0)
			(layer "F.Fab")
			(effects
				(font
					(size 1.27 1.27)
				)
			)
		)
		(duplicate_pad_numbers_are_jumpers no)
		(fp_circle
			(center 0 0)
			(end 5.8166 0)
			(stroke
				(width 0.1524)
				(type default)
			)
			(fill no)
			(layer "F.SilkS")
		)
		(fp_circle
			(center 0 0)
			(end 5.8166 0)
			(stroke
				(width 0.1524)
				(type default)
			)
			(fill no)
			(layer "B.SilkS")
		)
		(fp_circle
			(center 0 0)
			(end 5.8166 0)
			(stroke
				(width 0.1)
				(type default)
			)
			(fill no)
			(layer "B.Fab")
		)
		(fp_circle
			(center 0 0)
			(end 5.8166 0)
			(stroke
				(width 0.1)
				(type default)
			)
			(fill no)
			(layer "F.Fab")
		)
		(pad "" np_thru_hole circle
			(at 0 0)
			(size 10.0076 10.0076)
			(drill 10.0076)
			(layers "*.Cu" "*.Mask")
			(clearance 0.381)
			(thermal_gap 0.381)
		)
	)
	(footprint ""
		(layer "F.Cu")
		(at 403.682962 -59.4995 180)
		(property "Reference" "R476"
			(at 0 0 180)
			(layer "F.SilkS")
			(hide yes)
			(effects
				(font
					(size 1.27 1.27)
				)
			)
		)
		(property "Value" ""
			(at 0 0 180)
			(layer "F.Fab")
			(effects
				(font
					(size 1.27 1.27)
				)
			)
		)
		(duplicate_pad_numbers_are_jumpers no)
		(fp_line
			(start 0.7874 0.4064)
			(end -0.7874 0.4064)
			(stroke
				(width 0.1524)
				(type default)
			)
			(layer "F.SilkS")
		)
		(fp_line
			(start 0.7874 -0.4064)
			(end 0.7874 0.4064)
			(stroke
				(width 0.1524)
				(type default)
			)
			(layer "F.SilkS")
		)
		(fp_line
			(start -0.7874 0.4064)
			(end -0.7874 -0.4064)
			(stroke
				(width 0.1524)
				(type default)
			)
			(layer "F.SilkS")
		)
		(fp_line
			(start -0.7874 -0.4064)
			(end 0.7874 -0.4064)
			(stroke
				(width 0.1524)
				(type default)
			)
			(layer "F.SilkS")
		)
		(fp_line
			(start 0.67945 0.3048)
			(end 0.120396 0.3048)
			(stroke
				(width 0.1)
				(type default)
			)
			(layer "F.Fab")
		)
		(fp_line
			(start 0.67945 -0.3048)
			(end 0.67945 0.3048)
			(stroke
				(width 0.1)
				(type default)
			)
			(layer "F.Fab")
		)
		(fp_line
			(start 0.12065 -0.2794)
			(end 0.12065 -0.3048)
			(stroke
				(width 0.1)
				(type default)
			)
			(layer "F.Fab")
		)
		(fp_line
			(start 0.12065 -0.3048)
			(end 0.67945 -0.3048)
			(stroke
				(width 0.1)
				(type default)
			)
			(layer "F.Fab")
		)
		(fp_line
			(start 0.120396 0.3048)
			(end 0.120396 0.2794)
			(stroke
				(width 0.1)
				(type default)
			)
			(layer "F.Fab")
		)
		(fp_line
			(start 0.120396 0.2794)
			(end -0.12065 0.2794)
			(stroke
				(width 0.1)
				(type default)
			)
			(layer "F.Fab")
		)
		(fp_line
			(start -0.12065 0.3048)
			(end -0.67945 0.3048)
			(stroke
				(width 0.1)
				(type default)
			)
			(layer "F.Fab")
		)
		(fp_line
			(start -0.12065 0.2794)
			(end -0.12065 0.3048)
			(stroke
				(width 0.1)
				(type default)
			)
			(layer "F.Fab")
		)
		(fp_line
			(start -0.12065 -0.2794)
			(end 0.12065 -0.2794)
			(stroke
				(width 0.1)
				(type default)
			)
			(layer "F.Fab")
		)
		(fp_line
			(start -0.12065 -0.305054)
			(end -0.12065 -0.2794)
			(stroke
				(width 0.1)
				(type default)
			)
			(layer "F.Fab")
		)
		(fp_line
			(start -0.67945 0.3048)
			(end -0.67945 -0.305054)
			(stroke
				(width 0.1)
				(type default)
			)
			(layer "F.Fab")
		)
		(fp_line
			(start -0.67945 -0.305054)
			(end -0.12065 -0.305054)
			(stroke
				(width 0.1)
				(type default)
			)
			(layer "F.Fab")
		)
		(pad "1" smd circle
			(at -0.40005 0 180)
			(size 0 0)
			(layers "F.Cu" "F.Mask" "F.Paste")
			(net "CPU0_XTRIG_L6")
		)
		(pad "2" smd circle
			(at 0.40005 0 180)
			(size 0 0)
			(layers "F.Cu" "F.Mask" "F.Paste")
			(net "HDT_CPU0_XTRIG_L6")
		)
	)
	(footprint ""
		(layer "F.Cu")
		(at 130.067304 -54.17439 180)
		(property "Reference" "U152"
			(at -2.417064 -3.52171 0)
			(unlocked yes)
			(layer "F.SilkS")
			(effects
				(font
					(size 0.7874 0.5842)
					(thickness 0.1524)
				)
				(justify left)
			)
		)
		(property "Value" ""
			(at 0 0 180)
			(layer "F.Fab")
			(effects
				(font
					(size 1.27 1.27)
				)
			)
		)
		(duplicate_pad_numbers_are_jumpers no)
		(fp_line
			(start 1.245616 1.445768)
			(end -1.245616 1.445768)
			(stroke
				(width 0.1524)
				(type default)
			)
			(layer "F.SilkS")
		)
		(fp_line
			(start 1.245616 -1.445768)
			(end 1.245616 1.445768)
			(stroke
				(width 0.1524)
				(type default)
			)
			(layer "F.SilkS")
		)
		(fp_line
			(start -1.245616 1.445768)
			(end -1.245616 -1.445768)
			(stroke
				(width 0.1524)
				(type default)
			)
			(layer "F.SilkS")
		)
		(fp_line
			(start -1.245616 -1.445768)
			(end 1.245616 -1.445768)
			(stroke
				(width 0.1524)
				(type default)
			)
			(layer "F.SilkS")
		)
		(fp_poly
			(pts
				(xy -1.809496 -0.216662) (xy -2.317496 0.037338) (xy -2.317496 -0.470662)
			)
			(stroke
				(width 0)
				(type default)
			)
			(fill yes)
			(layer "F.SilkS")
		)
		(fp_line
			(start 0.724916 0.925068)
			(end -0.724916 0.925068)
			(stroke
				(width 0.1)
				(type default)
			)
			(layer "F.Fab")
		)
		(fp_line
			(start 0.724916 -0.925068)
			(end 0.724916 0.925068)
			(stroke
				(width 0.1)
				(type default)
			)
			(layer "F.Fab")
		)
		(fp_line
			(start -0.724916 0.925068)
			(end -0.724916 -0.925068)
			(stroke
				(width 0.1)
				(type default)
			)
			(layer "F.Fab")
		)
		(fp_line
			(start -0.724916 -0.925068)
			(end 0.724916 -0.925068)
			(stroke
				(width 0.1)
				(type default)
			)
			(layer "F.Fab")
		)
		(fp_poly
			(pts
				(xy -1.894586 -0.453898) (xy -1.894586 0.054102) (xy -1.386586 -0.199898)
			)
			(stroke
				(width 0)
				(type default)
			)
			(fill yes)
			(layer "F.Fab")
		)
		(pad "1" smd circle
			(at -0.649986 -0.199898 90)
			(size 0 0)
			(layers "F.Cu" "F.Mask" "F.Paste")
			(net "GND")
		)
		(pad "2" smd rect
			(at -0.700024 0.199898 270)
			(size 0.1778 0.8128)
			(layers "F.Cu" "F.Mask" "F.Paste")
			(net "U152_OE_N")
		)
		(pad "3" smd rect
			(at -0.40005 0.899922 180)
			(size 0.1778 0.8128)
			(layers "F.Cu" "F.Mask" "F.Paste")
			(net "GND")
		)
		(pad "4" smd rect
			(at 0 0.899922 180)
			(size 0.1778 0.8128)
			(layers "F.Cu" "F.Mask" "F.Paste")
			(net "JTAG_CPUX_TDO")
		)
		(pad "5" smd rect
			(at 0.40005 0.899922 180)
			(size 0.1778 0.8128)
			(layers "F.Cu" "F.Mask" "F.Paste")
			(net "JTAG_CPUX_TDI_R1")
		)
		(pad "6" smd rect
			(at 0.700024 0.199898 90)
			(size 0.1778 0.8128)
			(layers "F.Cu" "F.Mask" "F.Paste")
			(net "PVDD18_S5_P0")
		)
		(pad "7" smd rect
			(at 0.700024 -0.199898 90)
			(size 0.1778 0.8128)
			(layers "F.Cu" "F.Mask" "F.Paste")
			(net "PVDD18_S5_P0")
		)
		(pad "8" smd rect
			(at 0.40005 -0.899922 180)
			(size 0.1778 0.8128)
			(layers "F.Cu" "F.Mask" "F.Paste")
			(net "JTAG_TDI")
		)
		(pad "9" smd rect
			(at 0 -0.899922 180)
			(size 0.1778 0.8128)
			(layers "F.Cu" "F.Mask" "F.Paste")
			(net "JTAG_TDO_R")
		)
		(pad "10" smd rect
			(at -0.40005 -0.912622 180)
			(size 0.1778 0.7874)
			(layers "F.Cu" "F.Mask" "F.Paste")
			(net "PVDD18_S5_P0")
		)
	)
	(footprint ""
		(layer "F.Cu")
		(at 41.11244 -105.2195)
		(property "Reference" "C1113"
			(at 0 0 0)
			(layer "F.SilkS")
			(hide yes)
			(effects
				(font
					(size 1.27 1.27)
				)
			)
		)
		(property "Value" ""
			(at 0 0 0)
			(layer "F.Fab")
			(effects
				(font
					(size 1.27 1.27)
				)
			)
		)
		(duplicate_pad_numbers_are_jumpers no)
		(fp_line
			(start -1.524 -0.762)
			(end 1.524 -0.762)
			(stroke
				(width 0.1524)
				(type default)
			)
			(layer "F.SilkS")
		)
		(fp_line
			(start -1.524 0.762)
			(end -1.524 -0.762)
			(stroke
				(width 0.1524)
				(type default)
			)
			(layer "F.SilkS")
		)
		(fp_line
			(start 1.524 -0.762)
			(end 1.524 0.762)
			(stroke
				(width 0.1524)
				(type default)
			)
			(layer "F.SilkS")
		)
		(fp_line
			(start 1.524 0.762)
			(end -1.524 0.762)
			(stroke
				(width 0.1524)
				(type default)
			)
			(layer "F.SilkS")
		)
		(fp_line
			(start -1.1049 -0.724916)
			(end -1.1049 0.724916)
			(stroke
				(width 0.1)
				(type default)
			)
			(layer "F.Fab")
		)
		(fp_line
			(start -1.1049 0.724916)
			(end 1.1049 0.724916)
			(stroke
				(width 0.1)
				(type default)
			)
			(layer "F.Fab")
		)
		(fp_line
			(start 1.1049 -0.724916)
			(end -1.1049 -0.724916)
			(stroke
				(width 0.1)
				(type default)
			)
			(layer "F.Fab")
		)
		(fp_line
			(start 1.1049 0.724916)
			(end 1.1049 -0.724916)
			(stroke
				(width 0.1)
				(type default)
			)
			(layer "F.Fab")
		)
		(pad "1" smd rect
			(at -0.889 0 180)
			(size 1.016 1.27)
			(layers "F.Cu" "F.Mask" "F.Paste")
			(net "P12V_AUX_DSC_S1")
		)
		(pad "2" smd rect
			(at 0.889 0 180)
			(size 1.016 1.27)
			(layers "F.Cu" "F.Mask" "F.Paste")
			(net "GND")
		)
	)
)
